# S9S_MB_2U (Grand Teton) — schematic netlist excerpt (pin names and nets, part order shuffled) for the footprints in the layout excerpt that follows; sources: Cadence DE-HDL packaged netlist, KiCad conversion of 03242023_DA0F0TMBIJ0_F0T_Motherboard_J_brd_V01_OCP.brd

X4  TP_TDR_4P_FTS  TP_TDR_4P_DIP EMPTY  pkg TH  page 309
  S1  = TDR_DIFF_85_IN3_DP
  P1  = T1_GND
  P2  = T1_GND
  S2  = TDR_DIFF_85_IN3_DN

C1613  Q_CAP  0.1UF 25V 10% X7R  pkg 0402  page 236 : A = P3V3_AUX ; B = GND

(kicad_pcb
	(version 20260206)
	(generator "pcbnew")
	(generator_version "10.0")
	(general
		(thickness 1.6)
		(legacy_teardrops no)
	)
	(paper "A4")
	(title_block
		(title "03242023_DA0F0TMBIJ0_F0T_Motherboard_J_brd_V01_OCP.brd")
		(comment 1 "Grand Teton / footprints 843-844 of 6105")
	)
	(layers
		(0 "F.Cu" signal "TOP")
		(4 "In1.Cu" signal "GND")
		(6 "In2.Cu" signal "IN1")
		(8 "In3.Cu" signal "GND1")
		(10 "In4.Cu" signal "IN2")
		(12 "In5.Cu" signal "GND2")
		(14 "In6.Cu" signal "IN3")
		(16 "In7.Cu" signal "GND3")
		(18 "In8.Cu" signal "VCC")
		(20 "In9.Cu" signal "VCC1")
		(22 "In10.Cu" signal "GND4")
		(24 "In11.Cu" signal "IN4")
		(26 "In12.Cu" signal "GND5")
		(28 "In13.Cu" signal "IN5")
		(30 "In14.Cu" signal "GND6")
		(32 "In15.Cu" signal "IN6")
		(34 "In16.Cu" signal "GND7")
		(2 "B.Cu" signal "BOTTOM")
		(9 "F.Adhes" user "F.Adhesive")
		(11 "B.Adhes" user "B.Adhesive")
		(13 "F.Paste" user "Package Geometry/Pastemask Top")
		(15 "B.Paste" user "Package Geometry/Pastemask Bottom")
		(5 "F.SilkS" user "Ref Des/Silkscreen Top")
		(7 "B.SilkS" user "Ref Des/Silkscreen Bottom")
		(1 "F.Mask" user "Board Geometry/Soldermask Top")
		(3 "B.Mask" user "Board Geometry/Soldermask Bottom")
		(17 "Dwgs.User" user "User.Drawings")
		(19 "Cmts.User" user "User.Comments")
		(21 "Eco1.User" user "User.Eco1")
		(23 "Eco2.User" user "User.Eco2")
		(25 "Edge.Cuts" user "Board Geometry/Outline")
		(27 "Margin" user)
		(31 "F.CrtYd" user "Package Geometry/Place Bound Top")
		(29 "B.CrtYd" user "Package Geometry/Place Bound Bottom")
		(35 "F.Fab" user "Ref Des/Assembly Top")
		(33 "B.Fab" user "Ref Des/Assembly Bottom")
	)
	(footprint ""
		(layer "F.Cu")
		(at 495.90833 -153.174192 -90)
		(property "Reference" "X4"
			(at -1.336548 2.921 90)
			(unlocked yes)
			(layer "F.SilkS")
			(effects
				(font
					(size 0.7874 0.5842)
					(thickness 0.1524)
				)
				(justify left)
			)
		)
		(property "Value" ""
			(at 0 0 270)
			(layer "F.Fab")
			(effects
				(font
					(size 1.27 1.27)
				)
			)
		)
		(property "Device Type" "TP_TDR_4P_FTS_TH-TP_TDR_4P_DIPA"
			(at 1.30175 1.27 0)
			(unlocked yes)
			(layer "F.Fab")
			(hide yes)
			(effects
				(font
					(size 0.635 0.4064)
					(thickness 0.1524)
				)
			)
		)
		(property "User Part Number" "N_A"
			(at 1.30175 1.27 0)
			(unlocked yes)
			(layer "Cmts.User")
			(hide yes)
			(effects
				(font
					(size 0.635 0.4064)
					(thickness 0.1524)
				)
			)
		)
		(duplicate_pad_numbers_are_jumpers no)
		(fp_line
			(start 0 3.81)
			(end 2.54 3.81)
			(stroke
				(width 0.1524)
				(type default)
			)
			(layer "F.SilkS")
		)
		(fp_line
			(start 2.54 3.81)
			(end 2.54 3.6703)
			(stroke
				(width 0.1524)
				(type default)
			)
			(layer "F.SilkS")
		)
		(fp_line
			(start 0 3.175)
			(end 0 3.81)
			(stroke
				(width 0.1524)
				(type default)
			)
			(layer "F.SilkS")
		)
		(fp_line
			(start 2.54 1.4097)
			(end 2.54 1.1303)
			(stroke
				(width 0.1524)
				(type default)
			)
			(layer "F.SilkS")
		)
		(fp_line
			(start 0 0.635)
			(end 0 1.905)
			(stroke
				(width 0.1524)
				(type default)
			)
			(layer "F.SilkS")
		)
		(fp_line
			(start 2.54 -1.1303)
			(end 2.54 -1.27)
			(stroke
				(width 0.1524)
				(type default)
			)
			(layer "F.SilkS")
		)
		(fp_line
			(start 0 -1.27)
			(end 0 -0.635)
			(stroke
				(width 0.1524)
				(type default)
			)
			(layer "F.SilkS")
		)
		(fp_line
			(start 2.54 -1.27)
			(end 0 -1.27)
			(stroke
				(width 0.1524)
				(type default)
			)
			(layer "F.SilkS")
		)
		(fp_poly
			(pts
				(xy -0.761746 0) (xy -2.285746 0.762) (xy -2.285746 -0.762)
			)
			(stroke
				(width 0)
				(type default)
			)
			(fill yes)
			(layer "F.SilkS")
		)
		(fp_line
			(start 0 3.81)
			(end 2.54 3.81)
			(stroke
				(width 0.1)
				(type default)
			)
			(layer "F.Fab")
		)
		(fp_line
			(start 2.54 3.81)
			(end 2.54 -1.27)
			(stroke
				(width 0.1)
				(type default)
			)
			(layer "F.Fab")
		)
		(fp_line
			(start 0 -1.27)
			(end 0 3.81)
			(stroke
				(width 0.1)
				(type default)
			)
			(layer "F.Fab")
		)
		(fp_line
			(start 2.54 -1.27)
			(end 0 -1.27)
			(stroke
				(width 0.1)
				(type default)
			)
			(layer "F.Fab")
		)
		(fp_poly
			(pts
				(xy -0.761746 0) (xy -2.285746 -0.762) (xy -2.285746 0.762)
			)
			(stroke
				(width 0)
				(type default)
			)
			(fill yes)
			(layer "F.Fab")
		)
		(pad "1" thru_hole circle
			(at 0 0 270)
			(size 1.0033 1.0033)
			(drill 0.249936)
			(layers "*.Cu" "*.Mask")
			(remove_unused_layers no)
			(net "TDR_DIFF_85_IN3_DP")
			(clearance 0.10795)
			(thermal_gap 0.10795)
			(padstack
				(mode front_inner_back)
				(layer "Inner"
					(shape circle)
					(size 0.8001 0.8001)
					(clearance 0.1524)
				)
				(layer "B.Cu"
					(shape circle)
					(size 1.0033 1.0033)
					(clearance 0.10795)
				)
			)
		)
		(pad "2" thru_hole circle
			(at 2.54 0 270)
			(size 1.9939 1.9939)
			(drill 0.249936)
			(layers "*.Cu" "*.Mask")
			(remove_unused_layers no)
			(net "T1_GND")
			(clearance 0.10795)
			(thermal_gap 0.10795)
			(padstack
				(mode front_inner_back)
				(layer "Inner"
					(shape circle)
					(size 0.8001 0.8001)
					(clearance 0.1524)
				)
				(layer "B.Cu"
					(shape circle)
					(size 1.9939 1.9939)
					(clearance 0.10795)
				)
			)
		)
		(pad "3" thru_hole circle
			(at 2.54 2.54 270)
			(size 1.9939 1.9939)
			(drill 0.249936)
			(layers "*.Cu" "*.Mask")
			(remove_unused_layers no)
			(net "T1_GND")
			(clearance 0.10795)
			(thermal_gap 0.10795)
			(padstack
				(mode front_inner_back)
				(layer "Inner"
					(shape circle)
					(size 0.8001 0.8001)
					(clearance 0.1524)
				)
				(layer "B.Cu"
					(shape circle)
					(size 1.9939 1.9939)
					(clearance 0.10795)
				)
			)
		)
		(pad "4" thru_hole circle
			(at 0 2.54 270)
			(size 1.0033 1.0033)
			(drill 0.249936)
			(layers "*.Cu" "*.Mask")
			(remove_unused_layers no)
			(net "TDR_DIFF_85_IN3_DN")
			(clearance 0.10795)
			(thermal_gap 0.10795)
			(padstack
				(mode front_inner_back)
				(layer "Inner"
					(shape circle)
					(size 0.8001 0.8001)
					(clearance 0.1524)
				)
				(layer "B.Cu"
					(shape circle)
					(size 1.0033 1.0033)
					(clearance 0.10795)
				)
			)
		)
	)
	(footprint ""
		(layer "F.Cu")
		(at 149.898608 -73.285858 180)
		(property "Reference" "C1613"
			(at 0 0 180)
			(layer "F.SilkS")
			(hide yes)
			(effects
				(font
					(size 1.27 1.27)
				)
			)
		)
		(property "Value" ""
			(at 0 0 180)
			(layer "F.Fab")
			(effects
				(font
					(size 1.27 1.27)
				)
			)
		)
		(duplicate_pad_numbers_are_jumpers no)
		(fp_line
			(start 0.7874 0.4064)
			(end -0.7874 0.4064)
			(stroke
				(width 0.1524)
				(type default)
			)
			(layer "F.SilkS")
		)
		(fp_line
			(start 0.7874 -0.4064)
			(end 0.7874 0.4064)
			(stroke
				(width 0.1524)
				(type default)
			)
			(layer "F.SilkS")
		)
		(fp_line
			(start -0.7874 0.4064)
			(end -0.7874 -0.4064)
			(stroke
				(width 0.1524)
				(type default)
			)
			(layer "F.SilkS")
		)
		(fp_line
			(start -0.7874 -0.4064)
			(end 0.7874 -0.4064)
			(stroke
				(width 0.1524)
				(type default)
			)
			(layer "F.SilkS")
		)
		(fp_line
			(start 0.67945 0.3048)
			(end 0.120396 0.3048)
			(stroke
				(width 0.1)
				(type default)
			)
			(layer "F.Fab")
		)
		(fp_line
			(start 0.67945 -0.3048)
			(end 0.67945 0.3048)
			(stroke
				(width 0.1)
				(type default)
			)
			(layer "F.Fab")
		)
		(fp_line
			(start 0.12065 -0.2794)
			(end 0.12065 -0.3048)
			(stroke
				(width 0.1)
				(type default)
			)
			(layer "F.Fab")
		)
		(fp_line
			(start 0.12065 -0.3048)
			(end 0.67945 -0.3048)
			(stroke
				(width 0.1)
				(type default)
			)
			(layer "F.Fab")
		)
		(fp_line
			(start 0.120396 0.3048)
			(end 0.120396 0.2794)
			(stroke
				(width 0.1)
				(type default)
			)
			(layer "F.Fab")
		)
		(fp_line
			(start 0.120396 0.2794)
			(end -0.12065 0.2794)
			(stroke
				(width 0.1)
				(type default)
			)
			(layer "F.Fab")
		)
		(fp_line
			(start -0.12065 0.3048)
			(end -0.67945 0.3048)
			(stroke
				(width 0.1)
				(type default)
			)
			(layer "F.Fab")
		)
		(fp_line
			(start -0.12065 0.2794)
			(end -0.12065 0.3048)
			(stroke
				(width 0.1)
				(type default)
			)
			(layer "F.Fab")
		)
		(fp_line
			(start -0.12065 -0.2794)
			(end 0.12065 -0.2794)
			(stroke
				(width 0.1)
				(type default)
			)
			(layer "F.Fab")
		)
		(fp_line
			(start -0.12065 -0.305054)
			(end -0.12065 -0.2794)
			(stroke
				(width 0.1)
				(type default)
			)
			(layer "F.Fab")
		)
		(fp_line
			(start -0.67945 0.3048)
			(end -0.67945 -0.305054)
			(stroke
				(width 0.1)
				(type default)
			)
			(layer "F.Fab")
		)
		(fp_line
			(start -0.67945 -0.305054)
			(end -0.12065 -0.305054)
			(stroke
				(width 0.1)
				(type default)
			)
			(layer "F.Fab")
		)
		(pad "1" smd circle
			(at -0.40005 0 180)
			(size 0 0)
			(layers "F.Cu" "F.Mask" "F.Paste")
			(net "P3V3_AUX")
		)
		(pad "2" smd circle
			(at 0.40005 0 180)
			(size 0 0)
			(layers "F.Cu" "F.Mask" "F.Paste")
			(net "GND")
		)
	)
)
